(kicad_pcb
	(version 20260206)
	(generator "pcbnew")
	(generator_version "10.0")
	(general
		(thickness 1.6)
		(legacy_teardrops no)
	)
	(paper "A4")
	(title_block
		(title "04192023_DAF0TMB3IC0_F0TG_MB_C_brd_V02_OCP.brd")
		(comment 1 "Grand Teton / footprints 1104-1112 of 8354")
	)
	(layers
		(0 "F.Cu" signal "TOP")
		(4 "In1.Cu" signal "GND")
		(6 "In2.Cu" signal "IN1")
		(8 "In3.Cu" signal "GND1")
		(10 "In4.Cu" signal "IN2")
		(12 "In5.Cu" signal "GND2")
		(14 "In6.Cu" signal "IN3")
		(16 "In7.Cu" signal "GND3")
		(18 "In8.Cu" signal "VCC")
		(20 "In9.Cu" signal "VCC1")
		(22 "In10.Cu" signal "GND4")
		(24 "In11.Cu" signal "IN4")
		(26 "In12.Cu" signal "GND5")
		(28 "In13.Cu" signal "IN5")
		(30 "In14.Cu" signal "GND6")
		(32 "In15.Cu" signal "IN6")
		(34 "In16.Cu" signal "GND7")
		(2 "B.Cu" signal "BOTTOM")
		(9 "F.Adhes" user "F.Adhesive")
		(11 "B.Adhes" user "B.Adhesive")
		(13 "F.Paste" user "Package Geometry/Pastemask Top")
		(15 "B.Paste" user "Package Geometry/Pastemask Bottom")
		(5 "F.SilkS" user "Ref Des/Silkscreen Top")
		(7 "B.SilkS" user "Ref Des/Silkscreen Bottom")
		(1 "F.Mask" user "Board Geometry/Soldermask Top")
		(3 "B.Mask" user "Board Geometry/Soldermask Bottom")
		(17 "Dwgs.User" user "User.Drawings")
		(19 "Cmts.User" user "User.Comments")
		(21 "Eco1.User" user "User.Eco1")
		(23 "Eco2.User" user "User.Eco2")
		(25 "Edge.Cuts" user "Board Geometry/Outline")
		(27 "Margin" user)
		(31 "F.CrtYd" user "Package Geometry/Place Bound Top")
		(29 "B.CrtYd" user "Package Geometry/Place Bound Bottom")
		(35 "F.Fab" user "Ref Des/Assembly Top")
		(33 "B.Fab" user "Ref Des/Assembly Bottom")
	)
	(footprint ""
		(layer "F.Cu")
		(at 404.891748 -17.624298 90)
		(property "Reference" "C1559"
			(at 0 0 90)
			(layer "F.SilkS")
			(hide yes)
			(effects
				(font
					(size 1.27 1.27)
				)
			)
		)
		(property "Value" ""
			(at 0 0 90)
			(layer "F.Fab")
			(effects
				(font
					(size 1.27 1.27)
				)
			)
		)
		(duplicate_pad_numbers_are_jumpers no)
		(fp_line
			(start 0.299974 -0.150114)
			(end 0.299974 0.150114)
			(stroke
				(width 0.1)
				(type default)
			)
			(layer "F.Fab")
		)
		(fp_line
			(start -0.299974 -0.150114)
			(end 0.299974 -0.150114)
			(stroke
				(width 0.1)
				(type default)
			)
			(layer "F.Fab")
		)
		(fp_line
			(start 0.299974 0.150114)
			(end -0.299974 0.150114)
			(stroke
				(width 0.1)
				(type default)
			)
			(layer "F.Fab")
		)
		(fp_line
			(start -0.299974 0.150114)
			(end -0.299974 -0.150114)
			(stroke
				(width 0.1)
				(type default)
			)
			(layer "F.Fab")
		)
		(pad "1" smd rect
			(at -0.2667 0 90)
			(size 0.3048 0.381)
			(layers "F.Cu" "F.Mask" "F.Paste")
			(net "P5E_CPU0_G3_TX_C_DP<10>")
		)
		(pad "2" smd rect
			(at 0.2667 0 90)
			(size 0.3048 0.381)
			(layers "F.Cu" "F.Mask" "F.Paste")
			(net "P5E_CPU0_G3_TX_DP<10>")
		)
	)
	(footprint ""
		(layer "F.Cu")
		(at 80.498696 -178.0921 90)
		(property "Reference" "PC270"
			(at 0 0 90)
			(layer "F.SilkS")
			(hide yes)
			(effects
				(font
					(size 1.27 1.27)
				)
			)
		)
		(property "Value" ""
			(at 0 0 90)
			(layer "F.Fab")
			(effects
				(font
					(size 1.27 1.27)
				)
			)
		)
		(duplicate_pad_numbers_are_jumpers no)
		(fp_line
			(start 0.7874 -0.4064)
			(end 0.7874 0.4064)
			(stroke
				(width 0.1524)
				(type default)
			)
			(layer "F.SilkS")
		)
		(fp_line
			(start -0.7874 -0.4064)
			(end 0.7874 -0.4064)
			(stroke
				(width 0.1524)
				(type default)
			)
			(layer "F.SilkS")
		)
		(fp_line
			(start 0.7874 0.4064)
			(end -0.7874 0.4064)
			(stroke
				(width 0.1524)
				(type default)
			)
			(layer "F.SilkS")
		)
		(fp_line
			(start -0.7874 0.4064)
			(end -0.7874 -0.4064)
			(stroke
				(width 0.1524)
				(type default)
			)
			(layer "F.SilkS")
		)
		(fp_line
			(start -0.12065 -0.305054)
			(end -0.12065 -0.2794)
			(stroke
				(width 0.1)
				(type default)
			)
			(layer "F.Fab")
		)
		(fp_line
			(start -0.67945 -0.305054)
			(end -0.12065 -0.305054)
			(stroke
				(width 0.1)
				(type default)
			)
			(layer "F.Fab")
		)
		(fp_line
			(start 0.67945 -0.3048)
			(end 0.67945 0.3048)
			(stroke
				(width 0.1)
				(type default)
			)
			(layer "F.Fab")
		)
		(fp_line
			(start 0.12065 -0.3048)
			(end 0.67945 -0.3048)
			(stroke
				(width 0.1)
				(type default)
			)
			(layer "F.Fab")
		)
		(fp_line
			(start 0.12065 -0.2794)
			(end 0.12065 -0.3048)
			(stroke
				(width 0.1)
				(type default)
			)
			(layer "F.Fab")
		)
		(fp_line
			(start -0.12065 -0.2794)
			(end 0.12065 -0.2794)
			(stroke
				(width 0.1)
				(type default)
			)
			(layer "F.Fab")
		)
		(fp_line
			(start 0.120396 0.2794)
			(end -0.12065 0.2794)
			(stroke
				(width 0.1)
				(type default)
			)
			(layer "F.Fab")
		)
		(fp_line
			(start -0.12065 0.2794)
			(end -0.12065 0.3048)
			(stroke
				(width 0.1)
				(type default)
			)
			(layer "F.Fab")
		)
		(fp_line
			(start 0.67945 0.3048)
			(end 0.120396 0.3048)
			(stroke
				(width 0.1)
				(type default)
			)
			(layer "F.Fab")
		)
		(fp_line
			(start 0.120396 0.3048)
			(end 0.120396 0.2794)
			(stroke
				(width 0.1)
				(type default)
			)
			(layer "F.Fab")
		)
		(fp_line
			(start -0.12065 0.3048)
			(end -0.67945 0.3048)
			(stroke
				(width 0.1)
				(type default)
			)
			(layer "F.Fab")
		)
		(fp_line
			(start -0.67945 0.3048)
			(end -0.67945 -0.305054)
			(stroke
				(width 0.1)
				(type default)
			)
			(layer "F.Fab")
		)
		(pad "1" smd circle
			(at -0.40005 0 90)
			(size 0 0)
			(layers "F.Cu" "F.Mask" "F.Paste")
			(net "SW_PVDDCR_CPU0_P1_BOOT1_RC")
		)
		(pad "2" smd circle
			(at 0.40005 0 90)
			(size 0 0)
			(layers "F.Cu" "F.Mask" "F.Paste")
			(net "SW_PVDDCR_CPU0_P1_PH1")
		)
	)
	(footprint ""
		(layer "F.Cu")
		(at 49.009554 -375.49963 -90)
		(property "Reference" "C828"
			(at 0 0 270)
			(layer "F.SilkS")
			(hide yes)
			(effects
				(font
					(size 1.27 1.27)
				)
			)
		)
		(property "Value" ""
			(at 0 0 270)
			(layer "F.Fab")
			(effects
				(font
					(size 1.27 1.27)
				)
			)
		)
		(duplicate_pad_numbers_are_jumpers no)
		(fp_line
			(start -0.299974 0.150114)
			(end -0.299974 -0.150114)
			(stroke
				(width 0.1)
				(type default)
			)
			(layer "F.Fab")
		)
		(fp_line
			(start 0.299974 0.150114)
			(end -0.299974 0.150114)
			(stroke
				(width 0.1)
				(type default)
			)
			(layer "F.Fab")
		)
		(fp_line
			(start -0.299974 -0.150114)
			(end 0.299974 -0.150114)
			(stroke
				(width 0.1)
				(type default)
			)
			(layer "F.Fab")
		)
		(fp_line
			(start 0.299974 -0.150114)
			(end 0.299974 0.150114)
			(stroke
				(width 0.1)
				(type default)
			)
			(layer "F.Fab")
		)
		(pad "1" smd rect
			(at -0.2667 0 270)
			(size 0.3048 0.381)
			(layers "F.Cu" "F.Mask" "F.Paste")
			(net "P5E_CPU1_P0_TX_C_DN<4>")
		)
		(pad "2" smd rect
			(at 0.2667 0 270)
			(size 0.3048 0.381)
			(layers "F.Cu" "F.Mask" "F.Paste")
			(net "P5E_CPU1_P0_TX_DN<4>")
		)
	)
	(footprint ""
		(layer "F.Cu")
		(at 353.640644 -378.95403 -90)
		(property "Reference" "C941"
			(at 0 0 270)
			(layer "F.SilkS")
			(hide yes)
			(effects
				(font
					(size 1.27 1.27)
				)
			)
		)
		(property "Value" ""
			(at 0 0 270)
			(layer "F.Fab")
			(effects
				(font
					(size 1.27 1.27)
				)
			)
		)
		(duplicate_pad_numbers_are_jumpers no)
		(fp_line
			(start -0.299974 0.150114)
			(end -0.299974 -0.150114)
			(stroke
				(width 0.1)
				(type default)
			)
			(layer "F.Fab")
		)
		(fp_line
			(start 0.299974 0.150114)
			(end -0.299974 0.150114)
			(stroke
				(width 0.1)
				(type default)
			)
			(layer "F.Fab")
		)
		(fp_line
			(start -0.299974 -0.150114)
			(end 0.299974 -0.150114)
			(stroke
				(width 0.1)
				(type default)
			)
			(layer "F.Fab")
		)
		(fp_line
			(start 0.299974 -0.150114)
			(end 0.299974 0.150114)
			(stroke
				(width 0.1)
				(type default)
			)
			(layer "F.Fab")
		)
		(pad "1" smd rect
			(at -0.2667 0 270)
			(size 0.3048 0.381)
			(layers "F.Cu" "F.Mask" "F.Paste")
			(net "P5E_CPU0_P1_TX_C_DP<12>")
		)
		(pad "2" smd rect
			(at 0.2667 0 270)
			(size 0.3048 0.381)
			(layers "F.Cu" "F.Mask" "F.Paste")
			(net "P5E_CPU0_P1_TX_DP<12>")
		)
	)
	(footprint ""
		(layer "F.Cu")
		(at 109.332014 -405.633682 180)
		(property "Reference" "R6789"
			(at 0 0 180)
			(layer "F.SilkS")
			(hide yes)
			(effects
				(font
					(size 1.27 1.27)
				)
			)
		)
		(property "Value" ""
			(at 0 0 180)
			(layer "F.Fab")
			(effects
				(font
					(size 1.27 1.27)
				)
			)
		)
		(duplicate_pad_numbers_are_jumpers no)
		(fp_line
			(start 0.32512 0.175006)
			(end -0.32512 0.175006)
			(stroke
				(width 0.1)
				(type default)
			)
			(layer "F.Fab")
		)
		(fp_line
			(start 0.32512 -0.175006)
			(end 0.32512 0.175006)
			(stroke
				(width 0.1)
				(type default)
			)
			(layer "F.Fab")
		)
		(fp_line
			(start -0.32512 0.175006)
			(end -0.32512 -0.175006)
			(stroke
				(width 0.1)
				(type default)
			)
			(layer "F.Fab")
		)
		(fp_line
			(start -0.32512 -0.175006)
			(end 0.32512 -0.175006)
			(stroke
				(width 0.1)
				(type default)
			)
			(layer "F.Fab")
		)
		(pad "1" smd rect
			(at -0.2667 0 180)
			(size 0.3048 0.381)
			(layers "F.Cu" "F.Mask" "F.Paste")
			(net "U19_E2")
		)
		(pad "2" smd rect
			(at 0.2667 0)
			(size 0.3048 0.381)
			(layers "F.Cu" "F.Mask" "F.Paste")
			(net "GND")
		)
	)
	(footprint ""
		(layer "F.Cu")
		(at 440.592972 -22.816058 180)
		(property "Reference" "PR3838"
			(at 0 0 180)
			(layer "F.SilkS")
			(hide yes)
			(effects
				(font
					(size 1.27 1.27)
				)
			)
		)
		(property "Value" ""
			(at 0 0 180)
			(layer "F.Fab")
			(effects
				(font
					(size 1.27 1.27)
				)
			)
		)
		(duplicate_pad_numbers_are_jumpers no)
		(fp_line
			(start 0.7874 0.4064)
			(end -0.7874 0.4064)
			(stroke
				(width 0.1524)
				(type default)
			)
			(layer "F.SilkS")
		)
		(fp_line
			(start 0.7874 -0.4064)
			(end 0.7874 0.4064)
			(stroke
				(width 0.1524)
				(type default)
			)
			(layer "F.SilkS")
		)
		(fp_line
			(start -0.7874 0.4064)
			(end -0.7874 -0.4064)
			(stroke
				(width 0.1524)
				(type default)
			)
			(layer "F.SilkS")
		)
		(fp_line
			(start -0.7874 -0.4064)
			(end 0.7874 -0.4064)
			(stroke
				(width 0.1524)
				(type default)
			)
			(layer "F.SilkS")
		)
		(fp_line
			(start 0.67945 0.3048)
			(end 0.120396 0.3048)
			(stroke
				(width 0.1)
				(type default)
			)
			(layer "F.Fab")
		)
		(fp_line
			(start 0.67945 -0.3048)
			(end 0.67945 0.3048)
			(stroke
				(width 0.1)
				(type default)
			)
			(layer "F.Fab")
		)
		(fp_line
			(start 0.12065 -0.2794)
			(end 0.12065 -0.3048)
			(stroke
				(width 0.1)
				(type default)
			)
			(layer "F.Fab")
		)
		(fp_line
			(start 0.12065 -0.3048)
			(end 0.67945 -0.3048)
			(stroke
				(width 0.1)
				(type default)
			)
			(layer "F.Fab")
		)
		(fp_line
			(start 0.120396 0.3048)
			(end 0.120396 0.2794)
			(stroke
				(width 0.1)
				(type default)
			)
			(layer "F.Fab")
		)
		(fp_line
			(start 0.120396 0.2794)
			(end -0.12065 0.2794)
			(stroke
				(width 0.1)
				(type default)
			)
			(layer "F.Fab")
		)
		(fp_line
			(start -0.12065 0.3048)
			(end -0.67945 0.3048)
			(stroke
				(width 0.1)
				(type default)
			)
			(layer "F.Fab")
		)
		(fp_line
			(start -0.12065 0.2794)
			(end -0.12065 0.3048)
			(stroke
				(width 0.1)
				(type default)
			)
			(layer "F.Fab")
		)
		(fp_line
			(start -0.12065 -0.2794)
			(end 0.12065 -0.2794)
			(stroke
				(width 0.1)
				(type default)
			)
			(layer "F.Fab")
		)
		(fp_line
			(start -0.12065 -0.305054)
			(end -0.12065 -0.2794)
			(stroke
				(width 0.1)
				(type default)
			)
			(layer "F.Fab")
		)
		(fp_line
			(start -0.67945 0.3048)
			(end -0.67945 -0.305054)
			(stroke
				(width 0.1)
				(type default)
			)
			(layer "F.Fab")
		)
		(fp_line
			(start -0.67945 -0.305054)
			(end -0.12065 -0.305054)
			(stroke
				(width 0.1)
				(type default)
			)
			(layer "F.Fab")
		)
		(pad "1" smd circle
			(at -0.40005 0 180)
			(size 0 0)
			(layers "F.Cu" "F.Mask" "F.Paste")
			(net "P12V_OCP_SFF")
		)
		(pad "2" smd circle
			(at 0.40005 0 180)
			(size 0 0)
			(layers "F.Cu" "F.Mask" "F.Paste")
			(net "P12V_OCP_AVIN_PD_1")
		)
	)
	(footprint ""
		(layer "F.Cu")
		(at 171.174664 -120.464072)
		(property "Reference" "R6804"
			(at 0 0 0)
			(layer "F.SilkS")
			(hide yes)
			(effects
				(font
					(size 1.27 1.27)
				)
			)
		)
		(property "Value" ""
			(at 0 0 0)
			(layer "F.Fab")
			(effects
				(font
					(size 1.27 1.27)
				)
			)
		)
		(duplicate_pad_numbers_are_jumpers no)
		(fp_line
			(start -0.7874 -0.4064)
			(end 0.7874 -0.4064)
			(stroke
				(width 0.1524)
				(type default)
			)
			(layer "F.SilkS")
		)
		(fp_line
			(start -0.7874 0.4064)
			(end -0.7874 -0.4064)
			(stroke
				(width 0.1524)
				(type default)
			)
			(layer "F.SilkS")
		)
		(fp_line
			(start 0.7874 -0.4064)
			(end 0.7874 0.4064)
			(stroke
				(width 0.1524)
				(type default)
			)
			(layer "F.SilkS")
		)
		(fp_line
			(start 0.7874 0.4064)
			(end -0.7874 0.4064)
			(stroke
				(width 0.1524)
				(type default)
			)
			(layer "F.SilkS")
		)
		(fp_line
			(start -0.67945 -0.305054)
			(end -0.12065 -0.305054)
			(stroke
				(width 0.1)
				(type default)
			)
			(layer "F.Fab")
		)
		(fp_line
			(start -0.67945 0.3048)
			(end -0.67945 -0.305054)
			(stroke
				(width 0.1)
				(type default)
			)
			(layer "F.Fab")
		)
		(fp_line
			(start -0.12065 -0.305054)
			(end -0.12065 -0.2794)
			(stroke
				(width 0.1)
				(type default)
			)
			(layer "F.Fab")
		)
		(fp_line
			(start -0.12065 -0.2794)
			(end 0.12065 -0.2794)
			(stroke
				(width 0.1)
				(type default)
			)
			(layer "F.Fab")
		)
		(fp_line
			(start -0.12065 0.2794)
			(end -0.12065 0.3048)
			(stroke
				(width 0.1)
				(type default)
			)
			(layer "F.Fab")
		)
		(fp_line
			(start -0.12065 0.3048)
			(end -0.67945 0.3048)
			(stroke
				(width 0.1)
				(type default)
			)
			(layer "F.Fab")
		)
		(fp_line
			(start 0.120396 0.2794)
			(end -0.12065 0.2794)
			(stroke
				(width 0.1)
				(type default)
			)
			(layer "F.Fab")
		)
		(fp_line
			(start 0.120396 0.3048)
			(end 0.120396 0.2794)
			(stroke
				(width 0.1)
				(type default)
			)
			(layer "F.Fab")
		)
		(fp_line
			(start 0.12065 -0.3048)
			(end 0.67945 -0.3048)
			(stroke
				(width 0.1)
				(type default)
			)
			(layer "F.Fab")
		)
		(fp_line
			(start 0.12065 -0.2794)
			(end 0.12065 -0.3048)
			(stroke
				(width 0.1)
				(type default)
			)
			(layer "F.Fab")
		)
		(fp_line
			(start 0.67945 -0.3048)
			(end 0.67945 0.3048)
			(stroke
				(width 0.1)
				(type default)
			)
			(layer "F.Fab")
		)
		(fp_line
			(start 0.67945 0.3048)
			(end 0.120396 0.3048)
			(stroke
				(width 0.1)
				(type default)
			)
			(layer "F.Fab")
		)
		(pad "1" smd circle
			(at -0.40005 0)
			(size 0 0)
			(layers "F.Cu" "F.Mask" "F.Paste")
			(net "RST_RT_CPU0_P0_PERST_R_N")
		)
		(pad "2" smd circle
			(at 0.40005 0)
			(size 0 0)
			(layers "F.Cu" "F.Mask" "F.Paste")
			(net "RST_RT_CPU0_P0_PERST_R2_N")
		)
	)
	(footprint ""
		(layer "F.Cu")
		(at 330.932536 -388.149338)
		(property "Reference" "R677"
			(at 0 0 0)
			(layer "F.SilkS")
			(hide yes)
			(effects
				(font
					(size 1.27 1.27)
				)
			)
		)
		(property "Value" ""
			(at 0 0 0)
			(layer "F.Fab")
			(effects
				(font
					(size 1.27 1.27)
				)
			)
		)
		(duplicate_pad_numbers_are_jumpers no)
		(fp_line
			(start -0.32512 -0.175006)
			(end 0.32512 -0.175006)
			(stroke
				(width 0.1)
				(type default)
			)
			(layer "F.Fab")
		)
		(fp_line
			(start -0.32512 0.175006)
			(end -0.32512 -0.175006)
			(stroke
				(width 0.1)
				(type default)
			)
			(layer "F.Fab")
		)
		(fp_line
			(start 0.32512 -0.175006)
			(end 0.32512 0.175006)
			(stroke
				(width 0.1)
				(type default)
			)
			(layer "F.Fab")
		)
		(fp_line
			(start 0.32512 0.175006)
			(end -0.32512 0.175006)
			(stroke
				(width 0.1)
				(type default)
			)
			(layer "F.Fab")
		)
		(pad "1" smd rect
			(at -0.2667 0)
			(size 0.3048 0.381)
			(layers "F.Cu" "F.Mask" "F.Paste")
			(net "SMB_RT_CPU0_P1_ROM_MUX_1D_SDA")
		)
		(pad "2" smd rect
			(at 0.2667 0 180)
			(size 0.3048 0.381)
			(layers "F.Cu" "F.Mask" "F.Paste")
			(net "SMB_RT_CPU0_P1_ROM_MUX_1D_R_SDA")
		)
	)
	(footprint ""
		(layer "F.Cu")
		(at 193.55562 -422.804082 90)
		(property "Reference" "R2948"
			(at 0 0 90)
			(layer "F.SilkS")
			(hide yes)
			(effects
				(font
					(size 1.27 1.27)
				)
			)
		)
		(property "Value" ""
			(at 0 0 90)
			(layer "F.Fab")
			(effects
				(font
					(size 1.27 1.27)
				)
			)
		)
		(duplicate_pad_numbers_are_jumpers no)
		(fp_line
			(start 0.7874 -0.4064)
			(end 0.7874 0.4064)
			(stroke
				(width 0.1524)
				(type default)
			)
			(layer "F.SilkS")
		)
		(fp_line
			(start -0.7874 -0.4064)
			(end 0.7874 -0.4064)
			(stroke
				(width 0.1524)
				(type default)
			)
			(layer "F.SilkS")
		)
		(fp_line
			(start 0.7874 0.4064)
			(end -0.7874 0.4064)
			(stroke
				(width 0.1524)
				(type default)
			)
			(layer "F.SilkS")
		)
		(fp_line
			(start -0.7874 0.4064)
			(end -0.7874 -0.4064)
			(stroke
				(width 0.1524)
				(type default)
			)
			(layer "F.SilkS")
		)
		(fp_line
			(start -0.12065 -0.305054)
			(end -0.12065 -0.2794)
			(stroke
				(width 0.1)
				(type default)
			)
			(layer "F.Fab")
		)
		(fp_line
			(start -0.67945 -0.305054)
			(end -0.12065 -0.305054)
			(stroke
				(width 0.1)
				(type default)
			)
			(layer "F.Fab")
		)
		(fp_line
			(start 0.67945 -0.3048)
			(end 0.67945 0.3048)
			(stroke
				(width 0.1)
				(type default)
			)
			(layer "F.Fab")
		)
		(fp_line
			(start 0.12065 -0.3048)
			(end 0.67945 -0.3048)
			(stroke
				(width 0.1)
				(type default)
			)
			(layer "F.Fab")
		)
		(fp_line
			(start 0.12065 -0.2794)
			(end 0.12065 -0.3048)
			(stroke
				(width 0.1)
				(type default)
			)
			(layer "F.Fab")
		)
		(fp_line
			(start -0.12065 -0.2794)
			(end 0.12065 -0.2794)
			(stroke
				(width 0.1)
				(type default)
			)
			(layer "F.Fab")
		)
		(fp_line
			(start 0.120396 0.2794)
			(end -0.12065 0.2794)
			(stroke
				(width 0.1)
				(type default)
			)
			(layer "F.Fab")
		)
		(fp_line
			(start -0.12065 0.2794)
			(end -0.12065 0.3048)
			(stroke
				(width 0.1)
				(type default)
			)
			(layer "F.Fab")
		)
		(fp_line
			(start 0.67945 0.3048)
			(end 0.120396 0.3048)
			(stroke
				(width 0.1)
				(type default)
			)
			(layer "F.Fab")
		)
		(fp_line
			(start 0.120396 0.3048)
			(end 0.120396 0.2794)
			(stroke
				(width 0.1)
				(type default)
			)
			(layer "F.Fab")
		)
		(fp_line
			(start -0.12065 0.3048)
			(end -0.67945 0.3048)
			(stroke
				(width 0.1)
				(type default)
			)
			(layer "F.Fab")
		)
		(fp_line
			(start -0.67945 0.3048)
			(end -0.67945 -0.305054)
			(stroke
				(width 0.1)
				(type default)
			)
			(layer "F.Fab")
		)
		(pad "1" smd circle
			(at -0.40005 0 90)
			(size 0 0)
			(layers "F.Cu" "F.Mask" "F.Paste")
			(net "FM_GPU_HSC_EN_BUF_R")
		)
		(pad "2" smd circle
			(at 0.40005 0 90)
			(size 0 0)
			(layers "F.Cu" "F.Mask" "F.Paste")
			(net "GND")
		)
	)
)
